(kicad_pcb
	(version 20260206)
	(generator "pcbnew")
	(generator_version "10.0")
	(general
		(thickness 1.6)
		(legacy_teardrops no)
	)
	(paper "A4")
	(title_block
		(title "04192023_DAF0TMB3IC0_F0TG_MB_C_brd_V02_OCP.brd")
		(comment 1 "Grand Teton / footprints 6917-6922 of 8354")
	)
	(layers
		(0 "F.Cu" signal "TOP")
		(4 "In1.Cu" signal "GND")
		(6 "In2.Cu" signal "IN1")
		(8 "In3.Cu" signal "GND1")
		(10 "In4.Cu" signal "IN2")
		(12 "In5.Cu" signal "GND2")
		(14 "In6.Cu" signal "IN3")
		(16 "In7.Cu" signal "GND3")
		(18 "In8.Cu" signal "VCC")
		(20 "In9.Cu" signal "VCC1")
		(22 "In10.Cu" signal "GND4")
		(24 "In11.Cu" signal "IN4")
		(26 "In12.Cu" signal "GND5")
		(28 "In13.Cu" signal "IN5")
		(30 "In14.Cu" signal "GND6")
		(32 "In15.Cu" signal "IN6")
		(34 "In16.Cu" signal "GND7")
		(2 "B.Cu" signal "BOTTOM")
		(9 "F.Adhes" user "F.Adhesive")
		(11 "B.Adhes" user "B.Adhesive")
		(13 "F.Paste" user "Package Geometry/Pastemask Top")
		(15 "B.Paste" user "Package Geometry/Pastemask Bottom")
		(5 "F.SilkS" user "Ref Des/Silkscreen Top")
		(7 "B.SilkS" user "Ref Des/Silkscreen Bottom")
		(1 "F.Mask" user "Board Geometry/Soldermask Top")
		(3 "B.Mask" user "Board Geometry/Soldermask Bottom")
		(17 "Dwgs.User" user "User.Drawings")
		(19 "Cmts.User" user "User.Comments")
		(21 "Eco1.User" user "User.Eco1")
		(23 "Eco2.User" user "User.Eco2")
		(25 "Edge.Cuts" user "Board Geometry/Outline")
		(27 "Margin" user)
		(31 "F.CrtYd" user "Package Geometry/Place Bound Top")
		(29 "B.CrtYd" user "Package Geometry/Place Bound Bottom")
		(35 "F.Fab" user "Ref Des/Assembly Top")
		(33 "B.Fab" user "Ref Des/Assembly Bottom")
	)
	(footprint ""
		(layer "B.Cu")
		(at 85.852 -146.939)
		(property "Reference" "C296"
			(at 0 0 0)
			(layer "B.SilkS")
			(hide yes)
			(effects
				(font
					(size 1.27 1.27)
				)
				(justify mirror)
			)
		)
		(property "Value" ""
			(at 0 0 0)
			(layer "B.Fab")
			(effects
				(font
					(size 1.27 1.27)
				)
				(justify mirror)
			)
		)
		(duplicate_pad_numbers_are_jumpers no)
		(fp_line
			(start -0.7874 -0.4064)
			(end -0.7874 0.4064)
			(stroke
				(width 0.1524)
				(type default)
			)
			(layer "B.SilkS")
		)
		(fp_line
			(start -0.7874 0.4064)
			(end 0.7874 0.4064)
			(stroke
				(width 0.1524)
				(type default)
			)
			(layer "B.SilkS")
		)
		(fp_line
			(start 0.7874 -0.4064)
			(end -0.7874 -0.4064)
			(stroke
				(width 0.1524)
				(type default)
			)
			(layer "B.SilkS")
		)
		(fp_line
			(start 0.7874 0.4064)
			(end 0.7874 -0.4064)
			(stroke
				(width 0.1524)
				(type default)
			)
			(layer "B.SilkS")
		)
		(fp_line
			(start -0.67945 -0.3048)
			(end -0.67945 0.3048)
			(stroke
				(width 0.1)
				(type default)
			)
			(layer "B.Fab")
		)
		(fp_line
			(start -0.67945 0.3048)
			(end -0.120396 0.3048)
			(stroke
				(width 0.1)
				(type default)
			)
			(layer "B.Fab")
		)
		(fp_line
			(start -0.12065 -0.3048)
			(end -0.67945 -0.3048)
			(stroke
				(width 0.1)
				(type default)
			)
			(layer "B.Fab")
		)
		(fp_line
			(start -0.12065 -0.2794)
			(end -0.12065 -0.3048)
			(stroke
				(width 0.1)
				(type default)
			)
			(layer "B.Fab")
		)
		(fp_line
			(start -0.120396 0.2794)
			(end 0.12065 0.2794)
			(stroke
				(width 0.1)
				(type default)
			)
			(layer "B.Fab")
		)
		(fp_line
			(start -0.120396 0.3048)
			(end -0.120396 0.2794)
			(stroke
				(width 0.1)
				(type default)
			)
			(layer "B.Fab")
		)
		(fp_line
			(start 0.12065 -0.305054)
			(end 0.12065 -0.2794)
			(stroke
				(width 0.1)
				(type default)
			)
			(layer "B.Fab")
		)
		(fp_line
			(start 0.12065 -0.2794)
			(end -0.12065 -0.2794)
			(stroke
				(width 0.1)
				(type default)
			)
			(layer "B.Fab")
		)
		(fp_line
			(start 0.12065 0.2794)
			(end 0.12065 0.3048)
			(stroke
				(width 0.1)
				(type default)
			)
			(layer "B.Fab")
		)
		(fp_line
			(start 0.12065 0.3048)
			(end 0.67945 0.3048)
			(stroke
				(width 0.1)
				(type default)
			)
			(layer "B.Fab")
		)
		(fp_line
			(start 0.67945 -0.305054)
			(end 0.12065 -0.305054)
			(stroke
				(width 0.1)
				(type default)
			)
			(layer "B.Fab")
		)
		(fp_line
			(start 0.67945 0.3048)
			(end 0.67945 -0.305054)
			(stroke
				(width 0.1)
				(type default)
			)
			(layer "B.Fab")
		)
		(pad "1" smd circle
			(at 0.40005 0 180)
			(size 0 0)
			(layers "B.Cu" "B.Mask" "B.Paste")
			(net "SVID_PVDDCR_CPU0_P1_SVD_R")
		)
		(pad "2" smd circle
			(at -0.40005 0 180)
			(size 0 0)
			(layers "B.Cu" "B.Mask" "B.Paste")
			(net "GND")
		)
	)
	(footprint ""
		(layer "B.Cu")
		(at 136.040114 -38.914578)
		(property "Reference" "C6068"
			(at 0 0 0)
			(layer "B.SilkS")
			(hide yes)
			(effects
				(font
					(size 1.27 1.27)
				)
				(justify mirror)
			)
		)
		(property "Value" ""
			(at 0 0 0)
			(layer "B.Fab")
			(effects
				(font
					(size 1.27 1.27)
				)
				(justify mirror)
			)
		)
		(duplicate_pad_numbers_are_jumpers no)
		(fp_line
			(start -0.7874 -0.4064)
			(end -0.7874 0.4064)
			(stroke
				(width 0.1524)
				(type default)
			)
			(layer "B.SilkS")
		)
		(fp_line
			(start -0.7874 0.4064)
			(end 0.7874 0.4064)
			(stroke
				(width 0.1524)
				(type default)
			)
			(layer "B.SilkS")
		)
		(fp_line
			(start 0.7874 -0.4064)
			(end -0.7874 -0.4064)
			(stroke
				(width 0.1524)
				(type default)
			)
			(layer "B.SilkS")
		)
		(fp_line
			(start 0.7874 0.4064)
			(end 0.7874 -0.4064)
			(stroke
				(width 0.1524)
				(type default)
			)
			(layer "B.SilkS")
		)
		(fp_line
			(start -0.67945 -0.3048)
			(end -0.67945 0.3048)
			(stroke
				(width 0.1)
				(type default)
			)
			(layer "B.Fab")
		)
		(fp_line
			(start -0.67945 0.3048)
			(end -0.120396 0.3048)
			(stroke
				(width 0.1)
				(type default)
			)
			(layer "B.Fab")
		)
		(fp_line
			(start -0.12065 -0.3048)
			(end -0.67945 -0.3048)
			(stroke
				(width 0.1)
				(type default)
			)
			(layer "B.Fab")
		)
		(fp_line
			(start -0.12065 -0.2794)
			(end -0.12065 -0.3048)
			(stroke
				(width 0.1)
				(type default)
			)
			(layer "B.Fab")
		)
		(fp_line
			(start -0.120396 0.2794)
			(end 0.12065 0.2794)
			(stroke
				(width 0.1)
				(type default)
			)
			(layer "B.Fab")
		)
		(fp_line
			(start -0.120396 0.3048)
			(end -0.120396 0.2794)
			(stroke
				(width 0.1)
				(type default)
			)
			(layer "B.Fab")
		)
		(fp_line
			(start 0.12065 -0.305054)
			(end 0.12065 -0.2794)
			(stroke
				(width 0.1)
				(type default)
			)
			(layer "B.Fab")
		)
		(fp_line
			(start 0.12065 -0.2794)
			(end -0.12065 -0.2794)
			(stroke
				(width 0.1)
				(type default)
			)
			(layer "B.Fab")
		)
		(fp_line
			(start 0.12065 0.2794)
			(end 0.12065 0.3048)
			(stroke
				(width 0.1)
				(type default)
			)
			(layer "B.Fab")
		)
		(fp_line
			(start 0.12065 0.3048)
			(end 0.67945 0.3048)
			(stroke
				(width 0.1)
				(type default)
			)
			(layer "B.Fab")
		)
		(fp_line
			(start 0.67945 -0.305054)
			(end 0.12065 -0.305054)
			(stroke
				(width 0.1)
				(type default)
			)
			(layer "B.Fab")
		)
		(fp_line
			(start 0.67945 0.3048)
			(end 0.67945 -0.305054)
			(stroke
				(width 0.1)
				(type default)
			)
			(layer "B.Fab")
		)
		(pad "1" smd circle
			(at 0.40005 0 180)
			(size 0 0)
			(layers "B.Cu" "B.Mask" "B.Paste")
			(net "P1V2_AUX")
		)
		(pad "2" smd circle
			(at -0.40005 0 180)
			(size 0 0)
			(layers "B.Cu" "B.Mask" "B.Paste")
			(net "GND")
		)
	)
	(footprint ""
		(layer "B.Cu")
		(at 380.149354 -189.461648 90)
		(property "Reference" "PC108"
			(at 6.027928 1.101598 270)
			(unlocked yes)
			(layer "B.SilkS")
			(effects
				(font
					(size 0.7874 0.5842)
					(thickness 0.1524)
				)
				(justify left mirror)
			)
		)
		(property "Value" ""
			(at 0 0 90)
			(layer "B.Fab")
			(effects
				(font
					(size 1.27 1.27)
				)
				(justify mirror)
			)
		)
		(duplicate_pad_numbers_are_jumpers no)
		(fp_line
			(start 4.533392 -2.249932)
			(end -4.533392 -2.249932)
			(stroke
				(width 0.1524)
				(type default)
			)
			(layer "B.SilkS")
		)
		(fp_line
			(start -4.533392 -2.249932)
			(end -4.533392 2.249932)
			(stroke
				(width 0.1524)
				(type default)
			)
			(layer "B.SilkS")
		)
		(fp_line
			(start 4.533392 2.249932)
			(end 4.533392 -2.249932)
			(stroke
				(width 0.1524)
				(type default)
			)
			(layer "B.SilkS")
		)
		(fp_line
			(start -4.533392 2.249932)
			(end 4.533392 2.249932)
			(stroke
				(width 0.1524)
				(type default)
			)
			(layer "B.SilkS")
		)
		(fp_rect
			(start 4.533392 -2.326132)
			(end 5.39242 2.326132)
			(stroke
				(width 0)
				(type default)
			)
			(fill yes)
			(layer "B.SilkS")
		)
		(fp_line
			(start 3.750056 -2.249932)
			(end -3.750056 -2.249932)
			(stroke
				(width 0.1)
				(type default)
			)
			(layer "B.Fab")
		)
		(fp_line
			(start -3.750056 -2.249932)
			(end -3.750056 2.249932)
			(stroke
				(width 0.1)
				(type default)
			)
			(layer "B.Fab")
		)
		(fp_line
			(start 3.750056 2.249932)
			(end 3.750056 -2.249932)
			(stroke
				(width 0.1)
				(type default)
			)
			(layer "B.Fab")
		)
		(fp_line
			(start -3.750056 2.249932)
			(end 3.750056 2.249932)
			(stroke
				(width 0.1)
				(type default)
			)
			(layer "B.Fab")
		)
		(fp_text user "+"
			(at 6.322314 0.786384 0)
			(unlocked yes)
			(layer "B.SilkS")
			(effects
				(font
					(size 1.905 1.4224)
					(thickness 0.1524)
				)
				(justify left mirror)
			)
		)
		(fp_text user "-"
			(at -4.728718 1.129792 90)
			(unlocked yes)
			(layer "B.SilkS")
			(effects
				(font
					(size 1.905 1.4224)
					(thickness 0.1524)
				)
				(justify left mirror)
			)
		)
		(fp_text user "-"
			(at -4.8514 -0.14605 90)
			(unlocked yes)
			(layer "B.Fab")
			(effects
				(font
					(size 1.905 1.4224)
					(thickness 0.1524)
				)
				(justify left mirror)
			)
		)
		(fp_text user "+"
			(at 6.322314 0.786384 0)
			(unlocked yes)
			(layer "B.Fab")
			(effects
				(font
					(size 1.905 1.4224)
					(thickness 0.1524)
				)
				(justify left mirror)
			)
		)
		(pad "1" smd rect
			(at 3.199892 0 270)
			(size 2.413 2.8194)
			(layers "B.Cu" "B.Mask" "B.Paste")
			(net "PVDDCR_CPU0_P0")
		)
		(pad "2" smd rect
			(at -3.199892 0 270)
			(size 2.413 2.8194)
			(layers "B.Cu" "B.Mask" "B.Paste")
			(net "GND")
		)
	)
	(footprint ""
		(layer "B.Cu")
		(at 110.525814 -256.012442 -90)
		(property "Reference" "C2431"
			(at 0 0 90)
			(layer "B.SilkS")
			(hide yes)
			(effects
				(font
					(size 1.27 1.27)
				)
				(justify mirror)
			)
		)
		(property "Value" ""
			(at 0 0 90)
			(layer "B.Fab")
			(effects
				(font
					(size 1.27 1.27)
				)
				(justify mirror)
			)
		)
		(duplicate_pad_numbers_are_jumpers no)
		(fp_line
			(start -0.7874 0.4064)
			(end 0.7874 0.4064)
			(stroke
				(width 0.1524)
				(type default)
			)
			(layer "B.SilkS")
		)
		(fp_line
			(start 0.7874 0.4064)
			(end 0.7874 -0.4064)
			(stroke
				(width 0.1524)
				(type default)
			)
			(layer "B.SilkS")
		)
		(fp_line
			(start -0.7874 -0.4064)
			(end -0.7874 0.4064)
			(stroke
				(width 0.1524)
				(type default)
			)
			(layer "B.SilkS")
		)
		(fp_line
			(start 0.7874 -0.4064)
			(end -0.7874 -0.4064)
			(stroke
				(width 0.1524)
				(type default)
			)
			(layer "B.SilkS")
		)
		(fp_line
			(start -0.67945 0.3048)
			(end -0.120396 0.3048)
			(stroke
				(width 0.1)
				(type default)
			)
			(layer "B.Fab")
		)
		(fp_line
			(start -0.120396 0.3048)
			(end -0.120396 0.2794)
			(stroke
				(width 0.1)
				(type default)
			)
			(layer "B.Fab")
		)
		(fp_line
			(start 0.12065 0.3048)
			(end 0.67945 0.3048)
			(stroke
				(width 0.1)
				(type default)
			)
			(layer "B.Fab")
		)
		(fp_line
			(start 0.67945 0.3048)
			(end 0.67945 -0.305054)
			(stroke
				(width 0.1)
				(type default)
			)
			(layer "B.Fab")
		)
		(fp_line
			(start -0.120396 0.2794)
			(end 0.12065 0.2794)
			(stroke
				(width 0.1)
				(type default)
			)
			(layer "B.Fab")
		)
		(fp_line
			(start 0.12065 0.2794)
			(end 0.12065 0.3048)
			(stroke
				(width 0.1)
				(type default)
			)
			(layer "B.Fab")
		)
		(fp_line
			(start -0.12065 -0.2794)
			(end -0.12065 -0.3048)
			(stroke
				(width 0.1)
				(type default)
			)
			(layer "B.Fab")
		)
		(fp_line
			(start 0.12065 -0.2794)
			(end -0.12065 -0.2794)
			(stroke
				(width 0.1)
				(type default)
			)
			(layer "B.Fab")
		)
		(fp_line
			(start -0.67945 -0.3048)
			(end -0.67945 0.3048)
			(stroke
				(width 0.1)
				(type default)
			)
			(layer "B.Fab")
		)
		(fp_line
			(start -0.12065 -0.3048)
			(end -0.67945 -0.3048)
			(stroke
				(width 0.1)
				(type default)
			)
			(layer "B.Fab")
		)
		(fp_line
			(start 0.12065 -0.305054)
			(end 0.12065 -0.2794)
			(stroke
				(width 0.1)
				(type default)
			)
			(layer "B.Fab")
		)
		(fp_line
			(start 0.67945 -0.305054)
			(end 0.12065 -0.305054)
			(stroke
				(width 0.1)
				(type default)
			)
			(layer "B.Fab")
		)
		(pad "1" smd circle
			(at 0.40005 0 90)
			(size 0 0)
			(layers "B.Cu" "B.Mask" "B.Paste")
			(net "PVDDCR_SOC_P1")
		)
		(pad "2" smd circle
			(at -0.40005 0 90)
			(size 0 0)
			(layers "B.Cu" "B.Mask" "B.Paste")
			(net "GND")
		)
	)
	(footprint ""
		(layer "B.Cu")
		(at 355.263958 -272.284952 180)
		(property "Reference" "C2239"
			(at 0 0 0)
			(layer "B.SilkS")
			(hide yes)
			(effects
				(font
					(size 1.27 1.27)
				)
				(justify mirror)
			)
		)
		(property "Value" ""
			(at 0 0 0)
			(layer "B.Fab")
			(effects
				(font
					(size 1.27 1.27)
				)
				(justify mirror)
			)
		)
		(duplicate_pad_numbers_are_jumpers no)
		(fp_line
			(start 0.7874 0.4064)
			(end 0.7874 -0.4064)
			(stroke
				(width 0.1524)
				(type default)
			)
			(layer "B.SilkS")
		)
		(fp_line
			(start 0.7874 -0.4064)
			(end -0.7874 -0.4064)
			(stroke
				(width 0.1524)
				(type default)
			)
			(layer "B.SilkS")
		)
		(fp_line
			(start -0.7874 0.4064)
			(end 0.7874 0.4064)
			(stroke
				(width 0.1524)
				(type default)
			)
			(layer "B.SilkS")
		)
		(fp_line
			(start -0.7874 -0.4064)
			(end -0.7874 0.4064)
			(stroke
				(width 0.1524)
				(type default)
			)
			(layer "B.SilkS")
		)
		(fp_line
			(start 0.67945 0.3048)
			(end 0.67945 -0.305054)
			(stroke
				(width 0.1)
				(type default)
			)
			(layer "B.Fab")
		)
		(fp_line
			(start 0.67945 -0.305054)
			(end 0.12065 -0.305054)
			(stroke
				(width 0.1)
				(type default)
			)
			(layer "B.Fab")
		)
		(fp_line
			(start 0.12065 0.3048)
			(end 0.67945 0.3048)
			(stroke
				(width 0.1)
				(type default)
			)
			(layer "B.Fab")
		)
		(fp_line
			(start 0.12065 0.2794)
			(end 0.12065 0.3048)
			(stroke
				(width 0.1)
				(type default)
			)
			(layer "B.Fab")
		)
		(fp_line
			(start 0.12065 -0.2794)
			(end -0.12065 -0.2794)
			(stroke
				(width 0.1)
				(type default)
			)
			(layer "B.Fab")
		)
		(fp_line
			(start 0.12065 -0.305054)
			(end 0.12065 -0.2794)
			(stroke
				(width 0.1)
				(type default)
			)
			(layer "B.Fab")
		)
		(fp_line
			(start -0.120396 0.3048)
			(end -0.120396 0.2794)
			(stroke
				(width 0.1)
				(type default)
			)
			(layer "B.Fab")
		)
		(fp_line
			(start -0.120396 0.2794)
			(end 0.12065 0.2794)
			(stroke
				(width 0.1)
				(type default)
			)
			(layer "B.Fab")
		)
		(fp_line
			(start -0.12065 -0.2794)
			(end -0.12065 -0.3048)
			(stroke
				(width 0.1)
				(type default)
			)
			(layer "B.Fab")
		)
		(fp_line
			(start -0.12065 -0.3048)
			(end -0.67945 -0.3048)
			(stroke
				(width 0.1)
				(type default)
			)
			(layer "B.Fab")
		)
		(fp_line
			(start -0.67945 0.3048)
			(end -0.120396 0.3048)
			(stroke
				(width 0.1)
				(type default)
			)
			(layer "B.Fab")
		)
		(fp_line
			(start -0.67945 -0.3048)
			(end -0.67945 0.3048)
			(stroke
				(width 0.1)
				(type default)
			)
			(layer "B.Fab")
		)
		(pad "1" smd circle
			(at 0.40005 0)
			(size 0 0)
			(layers "B.Cu" "B.Mask" "B.Paste")
			(net "PVDDCR_CPU1_P0")
		)
		(pad "2" smd circle
			(at -0.40005 0)
			(size 0 0)
			(layers "B.Cu" "B.Mask" "B.Paste")
			(net "GND")
		)
	)
	(footprint ""
		(layer "B.Cu")
		(at 438.344564 -193.99631)
		(property "Reference" "C128"
			(at 0 0 0)
			(layer "B.SilkS")
			(hide yes)
			(effects
				(font
					(size 1.27 1.27)
				)
				(justify mirror)
			)
		)
		(property "Value" ""
			(at 0 0 0)
			(layer "B.Fab")
			(effects
				(font
					(size 1.27 1.27)
				)
				(justify mirror)
			)
		)
		(duplicate_pad_numbers_are_jumpers no)
		(fp_line
			(start -0.7874 -0.4064)
			(end -0.7874 0.4064)
			(stroke
				(width 0.1524)
				(type default)
			)
			(layer "B.SilkS")
		)
		(fp_line
			(start -0.7874 0.4064)
			(end 0.7874 0.4064)
			(stroke
				(width 0.1524)
				(type default)
			)
			(layer "B.SilkS")
		)
		(fp_line
			(start 0.7874 -0.4064)
			(end -0.7874 -0.4064)
			(stroke
				(width 0.1524)
				(type default)
			)
			(layer "B.SilkS")
		)
		(fp_line
			(start 0.7874 0.4064)
			(end 0.7874 -0.4064)
			(stroke
				(width 0.1524)
				(type default)
			)
			(layer "B.SilkS")
		)
		(fp_line
			(start -0.67945 -0.3048)
			(end -0.67945 0.3048)
			(stroke
				(width 0.1)
				(type default)
			)
			(layer "B.Fab")
		)
		(fp_line
			(start -0.67945 0.3048)
			(end -0.120396 0.3048)
			(stroke
				(width 0.1)
				(type default)
			)
			(layer "B.Fab")
		)
		(fp_line
			(start -0.12065 -0.3048)
			(end -0.67945 -0.3048)
			(stroke
				(width 0.1)
				(type default)
			)
			(layer "B.Fab")
		)
		(fp_line
			(start -0.12065 -0.2794)
			(end -0.12065 -0.3048)
			(stroke
				(width 0.1)
				(type default)
			)
			(layer "B.Fab")
		)
		(fp_line
			(start -0.120396 0.2794)
			(end 0.12065 0.2794)
			(stroke
				(width 0.1)
				(type default)
			)
			(layer "B.Fab")
		)
		(fp_line
			(start -0.120396 0.3048)
			(end -0.120396 0.2794)
			(stroke
				(width 0.1)
				(type default)
			)
			(layer "B.Fab")
		)
		(fp_line
			(start 0.12065 -0.305054)
			(end 0.12065 -0.2794)
			(stroke
				(width 0.1)
				(type default)
			)
			(layer "B.Fab")
		)
		(fp_line
			(start 0.12065 -0.2794)
			(end -0.12065 -0.2794)
			(stroke
				(width 0.1)
				(type default)
			)
			(layer "B.Fab")
		)
		(fp_line
			(start 0.12065 0.2794)
			(end 0.12065 0.3048)
			(stroke
				(width 0.1)
				(type default)
			)
			(layer "B.Fab")
		)
		(fp_line
			(start 0.12065 0.3048)
			(end 0.67945 0.3048)
			(stroke
				(width 0.1)
				(type default)
			)
			(layer "B.Fab")
		)
		(fp_line
			(start 0.67945 -0.305054)
			(end 0.12065 -0.305054)
			(stroke
				(width 0.1)
				(type default)
			)
			(layer "B.Fab")
		)
		(fp_line
			(start 0.67945 0.3048)
			(end 0.67945 -0.305054)
			(stroke
				(width 0.1)
				(type default)
			)
			(layer "B.Fab")
		)
		(pad "1" smd circle
			(at 0.40005 0 180)
			(size 0 0)
			(layers "B.Cu" "B.Mask" "B.Paste")
			(net "P3V3_AUX")
		)
		(pad "2" smd circle
			(at -0.40005 0 180)
			(size 0 0)
			(layers "B.Cu" "B.Mask" "B.Paste")
			(net "GND")
		)
	)
)
